(kicad_pcb
	(version 20260206)
	(generator "pcbnew")
	(generator_version "10.0")
	(general
		(thickness 1.21888)
		(legacy_teardrops no)
	)
	(paper "A4")
	(title_block
		(title "timecard-beta-v1 — TimeCard-DC-V1.PcbDoc")
		(comment 1 "Time Appliance Project (Time Card) / footprints 67-79 of 120")
	)
	(layers
		(0 "F.Cu" signal "TOP")
		(4 "In1.Cu" signal "SGND")
		(6 "In2.Cu" signal "IN1")
		(8 "In3.Cu" signal "IN2")
		(10 "In4.Cu" signal "SGND1")
		(2 "B.Cu" signal "BOTTOM")
		(9 "F.Adhes" user "F.Adhesive")
		(11 "B.Adhes" user "B.Adhesive")
		(13 "F.Paste" user "Top Paste")
		(15 "B.Paste" user "Bottom Paste")
		(5 "F.SilkS" user "Top Overlay")
		(7 "B.SilkS" user "Bottom Overlay")
		(1 "F.Mask" user "Top Solder")
		(3 "B.Mask" user "Bottom Solder")
		(17 "Dwgs.User" user "User.Drawings")
		(19 "Cmts.User" user "User.Comments")
		(21 "Eco1.User" user "User.Eco1")
		(23 "Eco2.User" user "User.Eco2")
		(25 "Edge.Cuts" user)
		(27 "Margin" user)
		(31 "F.CrtYd" user "Top Courtyard")
		(29 "B.CrtYd" user "Bottom Courtyard")
		(35 "F.Fab" user "Top Component Center")
		(33 "B.Fab" user "Bottom Component Center")
	)
	(footprint "SA53:SA53"
		(layer "F.Cu")
		(at 179.238595 116.5786)
		(property "Reference" "U10"
			(at -23.0214 27.776921 0)
			(unlocked yes)
			(layer "F.SilkS")
			(effects
				(font
					(size 0.762 0.762)
					(thickness 0.2286)
				)
			)
		)
		(property "Value" "MAC-SA5X"
			(at -18.30259 28.464002 0)
			(unlocked yes)
			(layer "F.SilkS")
			(hide yes)
			(effects
				(font
					(size 1.524 1.524)
					(thickness 0.254)
				)
			)
		)
		(sheetname "MAC")
		(sheetfile "MAC.kicad_sch")
		(duplicate_pad_numbers_are_jumpers no)
		(fp_line
			(start -24.53252 -24.05)
			(end 26.26748 -24.05)
			(stroke
				(width 0.254)
				(type solid)
			)
			(layer "F.SilkS")
		)
		(fp_line
			(start -24.53252 26.75)
			(end -24.53252 -24.05)
			(stroke
				(width 0.254)
				(type solid)
			)
			(layer "F.SilkS")
		)
		(fp_line
			(start -24.53252 26.75)
			(end 26.26748 26.75)
			(stroke
				(width 0.254)
				(type solid)
			)
			(layer "F.SilkS")
		)
		(fp_line
			(start 26.26748 26.75)
			(end 26.26748 -24.05)
			(stroke
				(width 0.254)
				(type solid)
			)
			(layer "F.SilkS")
		)
		(fp_circle
			(center -15.74748 3.64128)
			(end -15.74748 3.51428)
			(stroke
				(width 0.254)
				(type solid)
			)
			(fill no)
			(layer "F.SilkS")
		)
		(pad "1" smd rect
			(at -17.16748 3.64128 90)
			(size 0.25 1.8)
			(layers "F.Cu" "F.Mask" "F.Paste")
			(net "MAC_PPS_IN1+")
		)
		(pad "2" smd rect
			(at -21.16748 3.64128 90)
			(size 0.25 1.8)
			(layers "F.Cu" "F.Mask" "F.Paste")
			(net "MAC_USB+")
		)
		(pad "3" smd rect
			(at -17.16748 3.13328 90)
			(size 0.25 1.8)
			(layers "F.Cu" "F.Mask" "F.Paste")
			(net "MAC_PPS_IN1-")
		)
		(pad "4" smd rect
			(at -21.16748 3.13328 90)
			(size 0.25 1.8)
			(layers "F.Cu" "F.Mask" "F.Paste")
			(net "MAC_USB-")
		)
		(pad "5" smd rect
			(at -17.16748 2.62528 90)
			(size 0.25 1.8)
			(layers "F.Cu" "F.Mask" "F.Paste")
			(net "MAC_PPS_IN0+")
		)
		(pad "6" smd rect
			(at -21.16748 2.62528 90)
			(size 0.25 1.8)
			(layers "F.Cu" "F.Mask" "F.Paste")
			(net "MAC_USB_PWR")
		)
		(pad "7" smd rect
			(at -17.16748 2.11728 90)
			(size 0.25 1.8)
			(layers "F.Cu" "F.Mask" "F.Paste")
			(net "MAC_PPS_IN0-")
		)
		(pad "8" smd rect
			(at -21.16748 2.11728 90)
			(size 0.25 1.8)
			(layers "F.Cu" "F.Mask" "F.Paste")
			(net "GND")
		)
		(pad "9" smd rect
			(at -17.16748 1.60928 90)
			(size 0.25 1.8)
			(layers "F.Cu" "F.Mask" "F.Paste")
			(net "GND")
		)
		(pad "10" smd rect
			(at -21.16748 1.60928 90)
			(size 0.25 1.8)
			(layers "F.Cu" "F.Mask" "F.Paste")
		)
		(pad "11" smd rect
			(at -17.16748 1.10128 90)
			(size 0.25 1.8)
			(layers "F.Cu" "F.Mask" "F.Paste")
		)
		(pad "12" smd rect
			(at -21.16748 1.10128 90)
			(size 0.25 1.8)
			(layers "F.Cu" "F.Mask" "F.Paste")
		)
		(pad "13" smd rect
			(at -17.16748 0.59328 90)
			(size 0.25 1.8)
			(layers "F.Cu" "F.Mask" "F.Paste")
		)
		(pad "14" smd rect
			(at -21.16748 0.59328 90)
			(size 0.25 1.8)
			(layers "F.Cu" "F.Mask" "F.Paste")
		)
		(pad "15" smd rect
			(at -17.16748 0.08528 90)
			(size 0.25 1.8)
			(layers "F.Cu" "F.Mask" "F.Paste")
			(net "GND")
		)
		(pad "16" smd rect
			(at -21.16748 0.08528 90)
			(size 0.25 1.8)
			(layers "F.Cu" "F.Mask" "F.Paste")
		)
		(pad "17" smd rect
			(at -17.16748 -0.42272 90)
			(size 0.25 1.8)
			(layers "F.Cu" "F.Mask" "F.Paste")
			(net "MAC_PPS_OUT+")
		)
		(pad "18" smd rect
			(at -21.16748 -0.42272 90)
			(size 0.25 1.8)
			(layers "F.Cu" "F.Mask" "F.Paste")
		)
		(pad "19" smd rect
			(at -17.16748 -0.93072 90)
			(size 0.25 1.8)
			(layers "F.Cu" "F.Mask" "F.Paste")
			(net "MAC_PPS_OUT-")
		)
		(pad "20" smd rect
			(at -21.16748 -0.93072 90)
			(size 0.25 1.8)
			(layers "F.Cu" "F.Mask" "F.Paste")
			(net "MAC_ALARM")
		)
		(pad "P1" thru_hole circle
			(at 21.16748 21.65 270)
			(size 1.905 1.905)
			(drill 1.27)
			(layers "*.Cu" "*.Mask")
			(remove_unused_layers no)
			(net "MAC_FREQ_CTRL")
			(thermal_bridge_angle 90)
		)
		(pad "P2" thru_hole circle
			(at 21.16748 1.35 270)
			(size 1.905 1.905)
			(drill 1.27)
			(layers "*.Cu" "*.Mask")
			(remove_unused_layers no)
			(net "GND")
			(thermal_bridge_angle 90)
		)
		(pad "P3" thru_hole circle
			(at 21.16748 -18.95 270)
			(size 1.905 1.905)
			(drill 1.27)
			(layers "*.Cu" "*.Mask")
			(remove_unused_layers no)
			(net "MAC_RF_OUT")
			(thermal_bridge_angle 90)
		)
		(pad "P4" thru_hole circle
			(at -19.43252 -18.95 270)
			(size 1.905 1.905)
			(drill 1.27)
			(layers "*.Cu" "*.Mask")
			(remove_unused_layers no)
			(net "GND")
			(thermal_bridge_angle 90)
		)
		(pad "P5" thru_hole circle
			(at -19.43252 21.65 270)
			(size 1.905 1.905)
			(drill 1.27)
			(layers "*.Cu" "*.Mask")
			(remove_unused_layers no)
			(net "+5.0V")
			(thermal_bridge_angle 90)
		)
		(pad "P6" thru_hole circle
			(at -17.33251 -21.65 270)
			(size 1.905 1.905)
			(drill 1.27)
			(layers "*.Cu" "*.Mask")
			(remove_unused_layers no)
			(net "MAC_BITE")
			(thermal_bridge_angle 90)
		)
		(pad "P7" thru_hole circle
			(at -14.33252 -21.65 270)
			(size 1.905 1.905)
			(drill 1.27)
			(layers "*.Cu" "*.Mask")
			(remove_unused_layers no)
			(net "MAC_RX")
			(thermal_bridge_angle 90)
		)
		(pad "P8" thru_hole circle
			(at -11.33252 -21.65 270)
			(size 1.905 1.905)
			(drill 1.27)
			(layers "*.Cu" "*.Mask")
			(remove_unused_layers no)
			(net "MAC_TX")
			(thermal_bridge_angle 90)
		)
		(zone
			(layer "F.Cu")
			(hatch edge 0.5)
			(connect_pads
				(clearance 0)
			)
			(min_thickness 0.25)
			(keepout
				(tracks allowed)
				(vias allowed)
				(pads allowed)
				(copperpour not_allowed)
				(footprints allowed)
			)
			(placement
				(enabled no)
				(sheetname "")
			)
			(fill
				(thermal_gap 0.5)
				(thermal_bridge_width 0.5)
				(island_removal_mode 0)
			)
			(polygon
				(pts
					(xy 163.738595 113.0786) (xy 163.738595 123.0786) (xy 156.238595 123.0786) (xy 156.238595 113.0786)
				)
			)
		)
		(zone
			(layer "F.Cu")
			(hatch edge 0.5)
			(connect_pads
				(clearance 0)
			)
			(min_thickness 0.25)
			(keepout
				(tracks allowed)
				(vias allowed)
				(pads allowed)
				(copperpour not_allowed)
				(footprints allowed)
			)
			(placement
				(enabled no)
				(sheetname "")
			)
			(fill
				(thermal_gap 0.5)
				(thermal_bridge_width 0.5)
				(island_removal_mode 0)
			)
			(polygon
				(pts
					(xy 169.738595 99.0786) (xy 158.238595 99.0786) (xy 158.238595 93.0786) (xy 169.738595 93.0786)
				)
			)
		)
	)
	(footprint "Vault:RESC1608X55X25LL10T15"
		(layer "F.Cu")
		(at 190.738595 90.0786)
		(property "Reference" "R11"
			(at -2.771395 0.026921 0)
			(unlocked yes)
			(layer "F.SilkS")
			(effects
				(font
					(size 0.762 0.762)
					(thickness 0.2286)
				)
			)
		)
		(property "Value" "4.7K"
			(at -2.657602 2.60264 270)
			(unlocked yes)
			(layer "F.SilkS")
			(hide yes)
			(effects
				(font
					(size 1.524 1.524)
					(thickness 0.254)
				)
			)
		)
		(sheetname "MAC")
		(sheetfile "MAC.kicad_sch")
		(duplicate_pad_numbers_are_jumpers no)
		(pad "1" smd rect
			(at -0.65 0 90)
			(size 0.8 0.6)
			(layers "F.Cu" "F.Mask" "F.Paste")
			(net "GND")
		)
		(pad "2" smd rect
			(at 0.65 0 90)
			(size 0.8 0.6)
			(layers "F.Cu" "F.Mask" "F.Paste")
			(net "FPGA_MAC_PPS_IN0-")
		)
	)
	(footprint "Passives:FUSM1608X60N"
		(layer "F.Cu")
		(at 107.888595 144.1886 -90)
		(property "Reference" "F1"
			(at -1.61 -0.193345 90)
			(unlocked yes)
			(layer "F.SilkS")
			(effects
				(font
					(size 0.762 0.762)
					(thickness 0.2286)
				)
				(justify left bottom)
			)
		)
		(property "Value" "FUSE_0603_2.00A"
			(at 5.08039 2.1929 0)
			(unlocked yes)
			(layer "F.SilkS")
			(hide yes)
			(effects
				(font
					(size 1.524 1.524)
					(thickness 0.254)
				)
				(justify left bottom)
			)
		)
		(sheetname "POWER")
		(sheetfile "POWER.kicad_sch")
		(duplicate_pad_numbers_are_jumpers no)
		(fp_line
			(start 0 0.5)
			(end 0 -0.5)
			(stroke
				(width 0.1524)
				(type solid)
			)
			(layer "F.SilkS")
		)
		(pad "1" smd rect
			(at -0.69 0)
			(size 1 0.72)
			(layers "F.Cu" "F.Mask" "F.Paste")
			(net "NetD3_1")
		)
		(pad "2" smd rect
			(at 0.69 0)
			(size 1 0.72)
			(layers "F.Cu" "F.Mask" "F.Paste")
			(net "+12V")
		)
	)
	(footprint "Vault:TECO-1909763-1_V"
		(layer "F.Cu")
		(at 71.838595 137.5786 90)
		(property "Reference" "J10"
			(at -1.0214 2.926931 90)
			(unlocked yes)
			(layer "F.SilkS")
			(effects
				(font
					(size 0.762 0.762)
					(thickness 0.2286)
				)
			)
		)
		(property "Value" "1909763-1"
			(at 4.608085 3.749802 90)
			(unlocked yes)
			(layer "F.SilkS")
			(hide yes)
			(effects
				(font
					(size 1.524 1.524)
					(thickness 0.254)
				)
			)
		)
		(sheetname "USER_IO")
		(sheetfile "USER_IO.kicad_sch")
		(duplicate_pad_numbers_are_jumpers no)
		(fp_line
			(start -0.55 -1.3)
			(end 0.55 -1.3)
			(stroke
				(width 0.2)
				(type solid)
			)
			(layer "F.SilkS")
		)
		(fp_circle
			(center -1.778 1.65)
			(end -1.653 1.65)
			(stroke
				(width 0.25)
				(type solid)
			)
			(fill no)
			(layer "F.SilkS")
		)
		(pad "1" smd rect
			(at -1.475 0 90)
			(size 1.05 2.2)
			(layers "F.Cu" "F.Mask" "F.Paste")
			(net "GND")
		)
		(pad "2" smd rect
			(at 0 1.525 90)
			(size 1 1.05)
			(layers "F.Cu" "F.Mask" "F.Paste")
			(net "NetAN4_1")
		)
		(pad "3" smd rect
			(at 1.475 0 90)
			(size 1.05 2.2)
			(layers "F.Cu" "F.Mask" "F.Paste")
			(net "GND")
		)
	)
	(footprint "Passives:DIOM1608X06N"
		(layer "F.Cu")
		(at 215.788595 88.1786 -90)
		(property "Reference" "D4"
			(at -2 -0.393345 90)
			(unlocked yes)
			(layer "F.SilkS")
			(effects
				(font
					(size 0.762 0.762)
					(thickness 0.2286)
				)
				(justify left bottom)
			)
		)
		(property "Value" "RED"
			(at 3.22199 1.4097 0)
			(unlocked yes)
			(layer "F.SilkS")
			(hide yes)
			(effects
				(font
					(size 1.524 1.524)
					(thickness 0.254)
				)
				(justify left bottom)
			)
		)
		(sheetname "POWER")
		(sheetfile "POWER.kicad_sch")
		(duplicate_pad_numbers_are_jumpers no)
		(fp_circle
			(center -1.275 -0.725)
			(end -1.325 -0.725)
			(stroke
				(width 0.1)
				(type solid)
			)
			(fill no)
			(layer "F.SilkS")
		)
		(pad "1" smd rect
			(at -0.725 0)
			(size 0.85 1)
			(layers "F.Cu" "F.Mask" "F.Paste")
			(net "NetD4_1")
		)
		(pad "2" smd rect
			(at 0.725 0)
			(size 0.85 1)
			(layers "F.Cu" "F.Mask" "F.Paste")
			(net "+3.3V")
		)
	)
	(footprint "Vault:CAPC1608X87X45ML20T05"
		(layer "F.Cu")
		(at 130.988595 89.0786 -90)
		(property "Reference" "C25"
			(at -2.723069 -0.2286 0)
			(unlocked yes)
			(layer "F.SilkS")
			(effects
				(font
					(size 0.762 0.762)
					(thickness 0.2286)
				)
			)
		)
		(property "Value" "0.1uF"
			(at 2.09443 2.657602 270)
			(unlocked yes)
			(layer "F.SilkS")
			(hide yes)
			(effects
				(font
					(size 1.524 1.524)
					(thickness 0.254)
				)
			)
		)
		(sheetname "GPS_IMU_SENSORS")
		(sheetfile "GPS_IMU_SENSORS.kicad_sch")
		(duplicate_pad_numbers_are_jumpers no)
		(pad "1" smd rect
			(at -0.7 0)
			(size 1.1 1.05)
			(layers "F.Cu" "F.Mask" "F.Paste")
			(net "GND")
		)
		(pad "2" smd rect
			(at 0.7 0)
			(size 1.1 1.05)
			(layers "F.Cu" "F.Mask" "F.Paste")
			(net "+3.3V")
		)
	)
	(footprint "Vault:CAPC1608X87X45ML20T05"
		(layer "F.Cu")
		(at 86.488595 113.8286)
		(property "Reference" "C27"
			(at -2.79344 0.114181 0)
			(unlocked yes)
			(layer "F.SilkS")
			(effects
				(font
					(size 0.762 0.762)
					(thickness 0.2286)
				)
			)
		)
		(property "Value" "0.1uF"
			(at 2.09443 2.657602 0)
			(unlocked yes)
			(layer "F.SilkS")
			(hide yes)
			(effects
				(font
					(size 1.524 1.524)
					(thickness 0.254)
				)
			)
		)
		(sheetname "USER_IO")
		(sheetfile "USER_IO.kicad_sch")
		(duplicate_pad_numbers_are_jumpers no)
		(pad "1" smd rect
			(at -0.7 0 90)
			(size 1.1 1.05)
			(layers "F.Cu" "F.Mask" "F.Paste")
			(net "+3.3V")
		)
		(pad "2" smd rect
			(at 0.7 0 90)
			(size 1.1 1.05)
			(layers "F.Cu" "F.Mask" "F.Paste")
			(net "GND")
		)
	)
	(footprint "Vault:RESC1608X55X30NL15T15"
		(layer "F.Cu")
		(at 85.088595 56.9786 90)
		(property "Reference" "R29"
			(at -1.2 -1.206655 90)
			(unlocked yes)
			(layer "F.SilkS")
			(effects
				(font
					(size 0.762 0.762)
					(thickness 0.2286)
				)
				(justify left bottom)
			)
		)
		(property "Value" "200 OHM"
			(at -3.72999 -0.4445 0)
			(unlocked yes)
			(layer "F.SilkS")
			(hide yes)
			(effects
				(font
					(size 1.524 1.524)
					(thickness 0.254)
				)
				(justify left bottom)
			)
		)
		(sheetname "USER_IO")
		(sheetfile "USER_IO.kicad_sch")
		(duplicate_pad_numbers_are_jumpers no)
		(pad "1" smd rect
			(at -0.675 0 180)
			(size 0.95 0.8)
			(layers "F.Cu" "F.Mask" "F.Paste")
			(net "LED3")
		)
		(pad "2" smd rect
			(at 0.675 0 180)
			(size 0.95 0.8)
			(layers "F.Cu" "F.Mask" "F.Paste")
			(net "NetD13_1")
		)
	)
	(footprint "Vault:CAPC1608X87X45ML20T05"
		(layer "F.Cu")
		(at 144.238595 91.3786 90)
		(property "Reference" "C33"
			(at 3.2786 0.026931 90)
			(unlocked yes)
			(layer "F.SilkS")
			(effects
				(font
					(size 0.762 0.762)
					(thickness 0.2286)
				)
			)
		)
		(property "Value" "0.1uF"
			(at 2.09443 2.657602 90)
			(unlocked yes)
			(layer "F.SilkS")
			(hide yes)
			(effects
				(font
					(size 1.524 1.524)
					(thickness 0.254)
				)
			)
		)
		(sheetname "GPS_IMU_SENSORS")
		(sheetfile "GPS_IMU_SENSORS.kicad_sch")
		(duplicate_pad_numbers_are_jumpers no)
		(pad "1" smd rect
			(at -0.7 0 180)
			(size 1.1 1.05)
			(layers "F.Cu" "F.Mask" "F.Paste")
			(net "GND")
		)
		(pad "2" smd rect
			(at 0.7 0 180)
			(size 1.1 1.05)
			(layers "F.Cu" "F.Mask" "F.Paste")
			(net "+3.3V")
		)
	)
	(footprint "IntegratedCircuits:SOIC127P600X175-8N"
		(layer "F.Cu")
		(at 229.553595 110.8946)
		(property "Reference" "U1"
			(at -4.415 -2.972655 0)
			(unlocked yes)
			(layer "F.SilkS")
			(effects
				(font
					(size 0.762 0.762)
					(thickness 0.2286)
				)
				(justify left bottom)
			)
		)
		(property "Value" "MP1482DS-LF"
			(at -6.9469 5.15239 0)
			(unlocked yes)
			(layer "F.SilkS")
			(hide yes)
			(effects
				(font
					(size 1.524 1.524)
					(thickness 0.254)
				)
				(justify left bottom)
			)
		)
		(sheetname "POWER")
		(sheetfile "POWER.kicad_sch")
		(duplicate_pad_numbers_are_jumpers no)
		(fp_line
			(start -3.4 -2.5)
			(end 2 -2.5)
			(stroke
				(width 0.12)
				(type solid)
			)
			(layer "F.SilkS")
		)
		(fp_line
			(start -2 2.5)
			(end 2 2.5)
			(stroke
				(width 0.12)
				(type solid)
			)
			(layer "F.SilkS")
		)
		(pad "1" smd rect
			(at -2.475 -1.905)
			(size 1.97 0.57)
			(layers "F.Cu" "F.Mask" "F.Paste")
			(net "NetC4_1")
		)
		(pad "2" smd rect
			(at -2.475 -0.635)
			(size 1.97 0.57)
			(layers "F.Cu" "F.Mask" "F.Paste")
			(net "+12V")
		)
		(pad "3" smd rect
			(at -2.475 0.635)
			(size 1.97 0.57)
			(layers "F.Cu" "F.Mask" "F.Paste")
			(net "NetC4_2")
		)
		(pad "4" smd rect
			(at -2.475 1.905)
			(size 1.97 0.57)
			(layers "F.Cu" "F.Mask" "F.Paste")
			(net "GND")
		)
		(pad "5" smd rect
			(at 2.475 1.905)
			(size 1.97 0.57)
			(layers "F.Cu" "F.Mask" "F.Paste")
			(net "NetR4_2")
		)
		(pad "6" smd rect
			(at 2.475 0.635)
			(size 1.97 0.57)
			(layers "F.Cu" "F.Mask" "F.Paste")
			(net "NetC20_2")
		)
		(pad "7" smd rect
			(at 2.475 -0.635)
			(size 1.97 0.57)
			(layers "F.Cu" "F.Mask" "F.Paste")
			(net "NetR2_1")
		)
		(pad "8" smd rect
			(at 2.475 -1.905)
			(size 1.97 0.57)
			(layers "F.Cu" "F.Mask" "F.Paste")
			(net "NetC19_2")
		)
	)
	(footprint "Vault:CAPC1608X87X45ML20T05"
		(layer "F.Cu")
		(at 127.238595 80.0786 90)
		(property "Reference" "C61"
			(at -1.25 3.593345 90)
			(unlocked yes)
			(layer "F.SilkS")
			(effects
				(font
					(size 0.762 0.762)
					(thickness 0.2286)
				)
				(justify left bottom)
			)
		)
		(property "Value" "0.1uF"
			(at -3.47599 -0.2921 0)
			(unlocked yes)
			(layer "F.SilkS")
			(hide yes)
			(effects
				(font
					(size 1.524 1.524)
					(thickness 0.254)
				)
				(justify left bottom)
			)
		)
		(sheetname "GPS_IMU_SENSORS")
		(sheetfile "GPS_IMU_SENSORS.kicad_sch")
		(duplicate_pad_numbers_are_jumpers no)
		(pad "1" smd rect
			(at -0.7 0 180)
			(size 1.1 1.05)
			(layers "F.Cu" "F.Mask" "F.Paste")
			(net "GND")
		)
		(pad "2" smd rect
			(at 0.7 0 180)
			(size 1.1 1.05)
			(layers "F.Cu" "F.Mask" "F.Paste")
			(net "+5.0V")
		)
	)
	(footprint "Capacitors:CAPC1608X10N"
		(layer "F.Cu")
		(at 224.092595 110.1326 -90)
		(property "Reference" "C4"
			(at -2.029 -0.364345 90)
			(unlocked yes)
			(layer "F.SilkS")
			(effects
				(font
					(size 0.762 0.762)
					(thickness 0.2286)
				)
				(justify left bottom)
			)
		)
		(property "Value" "CAP_0603_0.01UF_50V"
			(at 3.14579 4.7879 0)
			(unlocked yes)
			(layer "F.SilkS")
			(hide yes)
			(effects
				(font
					(size 1.524 1.524)
					(thickness 0.254)
				)
				(justify left bottom)
			)
		)
		(sheetname "POWER")
		(sheetfile "POWER.kicad_sch")
		(duplicate_pad_numbers_are_jumpers no)
		(fp_line
			(start 0.635 0.7112)
			(end -0.635 0.7112)
			(stroke
				(width 0.1524)
				(type solid)
			)
			(layer "F.SilkS")
		)
		(fp_line
			(start 0.635 -0.7112)
			(end -0.635 -0.7112)
			(stroke
				(width 0.1524)
				(type solid)
			)
			(layer "F.SilkS")
		)
		(pad "1" smd rect
			(at -0.8 0)
			(size 0.95 1)
			(layers "F.Cu" "F.Mask" "F.Paste")
			(net "NetC4_1")
		)
		(pad "2" smd rect
			(at 0.8 0)
			(size 0.95 1)
			(layers "F.Cu" "F.Mask" "F.Paste")
			(net "NetC4_2")
		)
	)
	(footprint "Vault:CAPC1608X87X45ML20T05"
		(layer "F.Cu")
		(at 86.288595 119.5786 180)
		(property "Reference" "C29"
			(at -2.9286 -0.026931 360)
			(unlocked yes)
			(layer "F.SilkS")
			(effects
				(font
					(size 0.762 0.762)
					(thickness 0.2286)
				)
			)
		)
		(property "Value" "0.1uF"
			(at 2.09443 2.657602 180)
			(unlocked yes)
			(layer "F.SilkS")
			(hide yes)
			(effects
				(font
					(size 1.524 1.524)
					(thickness 0.254)
				)
			)
		)
		(sheetname "USER_IO")
		(sheetfile "USER_IO.kicad_sch")
		(duplicate_pad_numbers_are_jumpers no)
		(pad "1" smd rect
			(at -0.7 0 270)
			(size 1.1 1.05)
			(layers "F.Cu" "F.Mask" "F.Paste")
			(net "+3.3V")
		)
		(pad "2" smd rect
			(at 0.7 0 270)
			(size 1.1 1.05)
			(layers "F.Cu" "F.Mask" "F.Paste")
			(net "GND")
		)
	)
)
